(kicad_pcb
	(version 20260206)
	(generator "pcbnew")
	(generator_version "10.0")
	(general
		(thickness 1.6)
		(legacy_teardrops no)
	)
	(paper "A4")
	(title_block
		(title "v1-tray-backplane — T6M_tray_BP_c_1023_1120.brd")
		(comment 1 "Open CloudServer (Microsoft) / footprints 76-84 of 170")
	)
	(layers
		(0 "F.Cu" signal "TOP")
		(4 "In1.Cu" signal "GND")
		(6 "In2.Cu" signal "IN1")
		(8 "In3.Cu" signal "VCC")
		(10 "In4.Cu" signal "VCC1")
		(12 "In5.Cu" signal "IN2")
		(14 "In6.Cu" signal "GND1")
		(2 "B.Cu" signal "BOTTOM")
		(9 "F.Adhes" user "F.Adhesive")
		(11 "B.Adhes" user "B.Adhesive")
		(13 "F.Paste" user "Package Geometry/Pastemask Top")
		(15 "B.Paste" user "Package Geometry/Pastemask Bottom")
		(5 "F.SilkS" user "Ref Des/Silkscreen Top")
		(7 "B.SilkS" user "Ref Des/Silkscreen Bottom")
		(1 "F.Mask" user "Board Geometry/Soldermask Top")
		(3 "B.Mask" user "Board Geometry/Soldermask Bottom")
		(17 "Dwgs.User" user "User.Drawings")
		(19 "Cmts.User" user "User.Comments")
		(21 "Eco1.User" user "User.Eco1")
		(23 "Eco2.User" user "User.Eco2")
		(25 "Edge.Cuts" user "Board Geometry/Outline")
		(27 "Margin" user)
		(31 "F.CrtYd" user "Package Geometry/Place Bound Top")
		(29 "B.CrtYd" user "Package Geometry/Place Bound Bottom")
		(35 "F.Fab" user "Ref Des/Assembly Top")
		(33 "B.Fab" user "Ref Des/Assembly Bottom")
	)
	(footprint ""
		(layer "F.Cu")
		(at 89.41816 -27.574494 180)
		(property "Reference" "R44"
			(at 7.08152 -0.57404 0)
			(unlocked yes)
			(layer "F.SilkS")
			(effects
				(font
					(size 0.7874 0.5842)
					(thickness 0.1524)
				)
				(justify left)
			)
		)
		(property "Value" ""
			(at 0 0 180)
			(layer "F.Fab")
			(effects
				(font
					(size 1.27 1.27)
				)
			)
		)
		(duplicate_pad_numbers_are_jumpers no)
		(fp_line
			(start 0.7874 0.4064)
			(end -0.7874 0.4064)
			(stroke
				(width 0.1524)
				(type default)
			)
			(layer "F.SilkS")
		)
		(fp_line
			(start 0.7874 -0.4064)
			(end 0.7874 0.4064)
			(stroke
				(width 0.1524)
				(type default)
			)
			(layer "F.SilkS")
		)
		(fp_line
			(start -0.7874 0.4064)
			(end -0.7874 -0.4064)
			(stroke
				(width 0.1524)
				(type default)
			)
			(layer "F.SilkS")
		)
		(fp_line
			(start -0.7874 -0.4064)
			(end 0.7874 -0.4064)
			(stroke
				(width 0.1524)
				(type default)
			)
			(layer "F.SilkS")
		)
		(fp_poly
			(pts
				(xy -0.508 0.2794) (xy -0.508 0.2286) (xy -0.635 0.2286) (xy -0.635 -0.254) (xy -0.5334 -0.254)
				(xy -0.5334 -0.2794) (xy 0.5334 -0.2794) (xy 0.5334 -0.254) (xy 0.635 -0.254) (xy 0.635 0.254) (xy 0.5334 0.254)
				(xy 0.5334 0.2794)
			)
			(stroke
				(width 0)
				(type default)
			)
			(fill no)
			(layer "F.CrtYd")
		)
		(pad "1" smd rect
			(at 0.40005 0 180)
			(size 0.4572 0.508)
			(layers "F.Cu" "F.Mask" "F.Paste")
			(net "GND")
		)
		(pad "2" smd rect
			(at -0.40005 0 180)
			(size 0.4572 0.508)
			(layers "F.Cu" "F.Mask" "F.Paste")
			(net "ENET10G_2_RS0")
		)
	)
	(footprint ""
		(layer "F.Cu")
		(at 424.310048 -4.700016 180)
		(property "Reference" "H8"
			(at 1.428496 9.335516 0)
			(unlocked yes)
			(layer "F.SilkS")
			(effects
				(font
					(size 0.7874 0.5842)
					(thickness 0.1524)
				)
				(justify left)
			)
		)
		(property "Value" ""
			(at 0 0 180)
			(layer "F.Fab")
			(effects
				(font
					(size 1.27 1.27)
				)
			)
		)
		(duplicate_pad_numbers_are_jumpers no)
		(fp_circle
			(center 0 0)
			(end -7.999984 0)
			(stroke
				(width 0.1524)
				(type default)
			)
			(fill no)
			(layer "F.SilkS")
		)
		(fp_arc
			(start 7.999984 0)
			(mid 7.10586 3.675167)
			(end 4.623308 6.528816)
			(stroke
				(width 0.1524)
				(type default)
			)
			(layer "B.SilkS")
		)
		(fp_arc
			(start -4.623308 6.528816)
			(mid -3.675236 -7.105871)
			(end 7.999984 0)
			(stroke
				(width 0.1524)
				(type default)
			)
			(layer "B.SilkS")
		)
		(fp_circle
			(center 0 0)
			(end -14.5034 0)
			(stroke
				(width 0.1524)
				(type default)
			)
			(fill no)
			(layer "B.SilkS")
		)
		(fp_poly
			(pts
				(arc
					(start -4.5085 0)
					(mid 4.5085 0)
					(end -4.5085 0)
				)
			)
			(stroke
				(width 0)
				(type default)
			)
			(fill no)
			(layer "F.CrtYd")
		)
		(pad "" np_thru_hole circle
			(at 0 0 180)
			(size 3.6068 3.6068)
			(drill 3.6068)
			(layers "*.Cu" "*.Mask")
			(clearance 0.381)
			(thermal_gap 0.381)
		)
		(pad "2" thru_hole circle
			(at 3.41122 0 180)
			(size 0.762 0.762)
			(drill 0.5588)
			(layers "*.Cu" "*.Mask")
			(remove_unused_layers no)
			(net "GND")
			(clearance 0.1524)
			(thermal_gap 0.1524)
		)
		(pad "3" thru_hole circle
			(at 2.411984 -2.411984 180)
			(size 0.762 0.762)
			(drill 0.5588)
			(layers "*.Cu" "*.Mask")
			(remove_unused_layers no)
			(net "GND")
			(clearance 0.1524)
			(thermal_gap 0.1524)
		)
		(pad "4" thru_hole circle
			(at 0 -3.41122 180)
			(size 0.762 0.762)
			(drill 0.5588)
			(layers "*.Cu" "*.Mask")
			(remove_unused_layers no)
			(net "GND")
			(clearance 0.1524)
			(thermal_gap 0.1524)
		)
		(pad "5" thru_hole circle
			(at -2.411984 -2.411984 180)
			(size 0.762 0.762)
			(drill 0.5588)
			(layers "*.Cu" "*.Mask")
			(remove_unused_layers no)
			(net "GND")
			(clearance 0.1524)
			(thermal_gap 0.1524)
		)
		(pad "6" thru_hole circle
			(at -3.41122 0 180)
			(size 0.762 0.762)
			(drill 0.5588)
			(layers "*.Cu" "*.Mask")
			(remove_unused_layers no)
			(net "GND")
			(clearance 0.1524)
			(thermal_gap 0.1524)
		)
		(pad "7" thru_hole circle
			(at -2.411984 2.411984 180)
			(size 0.762 0.762)
			(drill 0.5588)
			(layers "*.Cu" "*.Mask")
			(remove_unused_layers no)
			(net "GND")
			(clearance 0.1524)
			(thermal_gap 0.1524)
		)
		(pad "8" thru_hole circle
			(at 0 3.41122 180)
			(size 0.762 0.762)
			(drill 0.5588)
			(layers "*.Cu" "*.Mask")
			(remove_unused_layers no)
			(net "GND")
			(clearance 0.1524)
			(thermal_gap 0.1524)
		)
		(pad "9" thru_hole circle
			(at 2.411984 2.411984 180)
			(size 0.762 0.762)
			(drill 0.5588)
			(layers "*.Cu" "*.Mask")
			(remove_unused_layers no)
			(net "GND")
			(clearance 0.1524)
			(thermal_gap 0.1524)
		)
		(zone
			(layer "F.Cu")
			(hatch none 0.5)
			(connect_pads
				(clearance 0)
			)
			(min_thickness 0.25)
			(keepout
				(tracks not_allowed)
				(vias allowed)
				(pads allowed)
				(copperpour not_allowed)
				(footprints allowed)
			)
			(placement
				(enabled no)
				(sheetname "")
			)
			(fill
				(thermal_gap 0.5)
				(thermal_bridge_width 0.5)
				(island_removal_mode 0)
			)
			(polygon
				(pts
					(arc
						(start 424.310048 3.299968)
						(mid 418.653205 0.956827)
						(end 416.310064 -4.700016)
					)
					(arc
						(start 416.310064 -4.700016)
						(mid 418.653205 -10.356859)
						(end 424.310048 -12.7)
					)
					(arc
						(start 424.310048 -9.462516)
						(mid 419.547548 -4.700016)
						(end 424.310048 0.062484)
					)
				)
			)
		)
		(zone
			(layers "F.Cu" "B.Cu" "In1.Cu" "In2.Cu" "In3.Cu" "In4.Cu" "In5.Cu" "In6.Cu")
			(hatch none 0.5)
			(connect_pads
				(clearance 0)
			)
			(min_thickness 0.25)
			(keepout
				(tracks not_allowed)
				(vias allowed)
				(pads allowed)
				(copperpour not_allowed)
				(footprints allowed)
			)
			(placement
				(enabled no)
				(sheetname "")
			)
			(fill
				(thermal_gap 0.5)
				(thermal_bridge_width 0.5)
				(island_removal_mode 0)
			)
			(polygon
				(pts
					(arc
						(start 426.621448 -4.700016)
						(mid 421.998648 -4.700016)
						(end 426.621448 -4.700016)
					)
				)
			)
		)
		(zone
			(layer "B.Cu")
			(hatch none 0.5)
			(connect_pads
				(clearance 0)
			)
			(min_thickness 0.25)
			(keepout
				(tracks not_allowed)
				(vias allowed)
				(pads allowed)
				(copperpour not_allowed)
				(footprints allowed)
			)
			(placement
				(enabled no)
				(sheetname "")
			)
			(fill
				(thermal_gap 0.5)
				(thermal_bridge_width 0.5)
				(island_removal_mode 0)
			)
			(polygon
				(pts
					(arc
						(start 424.310048 -15.225522)
						(mid 421.110024 -13.900028)
						(end 419.78453 -10.700004)
					)
					(arc
						(start 419.78453 -4.700016)
						(mid 421.110024 -1.499992)
						(end 424.310048 -0.174498)
					)
					(arc
						(start 424.310048 0.308102)
						(mid 420.768774 -1.158742)
						(end 419.30193 -4.700016)
					)
					(arc
						(start 419.30193 -10.700004)
						(mid 420.768864 -14.241114)
						(end 424.310048 -15.707868)
					)
				)
			)
		)
	)
	(footprint ""
		(layer "F.Cu")
		(at 365.2266 -3.0988 90)
		(property "Reference" "C30"
			(at -2.3114 -2.174748 90)
			(unlocked yes)
			(layer "F.SilkS")
			(effects
				(font
					(size 0.7874 0.5842)
					(thickness 0.1524)
				)
				(justify left)
			)
		)
		(property "Value" ""
			(at 0 0 90)
			(layer "F.Fab")
			(effects
				(font
					(size 1.27 1.27)
				)
			)
		)
		(duplicate_pad_numbers_are_jumpers no)
		(fp_line
			(start 0.7874 -0.4064)
			(end 0.7874 0.4064)
			(stroke
				(width 0.1524)
				(type default)
			)
			(layer "F.SilkS")
		)
		(fp_line
			(start -0.7874 -0.4064)
			(end 0.7874 -0.4064)
			(stroke
				(width 0.1524)
				(type default)
			)
			(layer "F.SilkS")
		)
		(fp_line
			(start 0 0.381)
			(end 0 -0.381)
			(stroke
				(width 0.1524)
				(type default)
			)
			(layer "F.SilkS")
		)
		(fp_line
			(start 0.7874 0.4064)
			(end -0.7874 0.4064)
			(stroke
				(width 0.1524)
				(type default)
			)
			(layer "F.SilkS")
		)
		(fp_line
			(start -0.7874 0.4064)
			(end -0.7874 -0.4064)
			(stroke
				(width 0.1524)
				(type default)
			)
			(layer "F.SilkS")
		)
		(fp_poly
			(pts
				(xy -0.5334 0.254) (xy -0.635 0.254) (xy -0.635 0.2286) (xy -0.635 -0.254) (xy -0.5334 -0.254) (xy -0.5334 -0.2794)
				(xy 0.5334 -0.2794) (xy 0.5334 -0.254) (xy 0.635 -0.254) (xy 0.635 0.254) (xy 0.5334 0.254) (xy 0.5334 0.2794)
				(xy -0.508 0.2794) (xy -0.5334 0.2794)
			)
			(stroke
				(width 0)
				(type default)
			)
			(fill no)
			(layer "F.CrtYd")
		)
		(pad "1" smd rect
			(at 0.40005 0 90)
			(size 0.4572 0.508)
			(layers "F.Cu" "F.Mask" "F.Paste")
			(net "P3V3_10G_3_VCCR")
		)
		(pad "2" smd rect
			(at -0.40005 0 90)
			(size 0.4572 0.508)
			(layers "F.Cu" "F.Mask" "F.Paste")
			(net "GND")
		)
	)
	(footprint ""
		(layer "F.Cu")
		(at 117.31244 -26.54681)
		(property "Reference" "R14"
			(at -61.341 5.115052 0)
			(unlocked yes)
			(layer "F.SilkS")
			(effects
				(font
					(size 0.7874 0.5842)
					(thickness 0.1524)
				)
				(justify left)
			)
		)
		(property "Value" ""
			(at 0 0 0)
			(layer "F.Fab")
			(effects
				(font
					(size 1.27 1.27)
				)
			)
		)
		(duplicate_pad_numbers_are_jumpers no)
		(fp_line
			(start -0.7874 -0.4064)
			(end 0.7874 -0.4064)
			(stroke
				(width 0.1524)
				(type default)
			)
			(layer "F.SilkS")
		)
		(fp_line
			(start -0.7874 0.4064)
			(end -0.7874 -0.4064)
			(stroke
				(width 0.1524)
				(type default)
			)
			(layer "F.SilkS")
		)
		(fp_line
			(start 0.7874 -0.4064)
			(end 0.7874 0.4064)
			(stroke
				(width 0.1524)
				(type default)
			)
			(layer "F.SilkS")
		)
		(fp_line
			(start 0.7874 0.4064)
			(end -0.7874 0.4064)
			(stroke
				(width 0.1524)
				(type default)
			)
			(layer "F.SilkS")
		)
		(fp_poly
			(pts
				(xy -0.508 0.2794) (xy -0.508 0.2286) (xy -0.635 0.2286) (xy -0.635 -0.254) (xy -0.5334 -0.254)
				(xy -0.5334 -0.2794) (xy 0.5334 -0.2794) (xy 0.5334 -0.254) (xy 0.635 -0.254) (xy 0.635 0.254) (xy 0.5334 0.254)
				(xy 0.5334 0.2794)
			)
			(stroke
				(width 0)
				(type default)
			)
			(fill no)
			(layer "F.CrtYd")
		)
		(pad "1" smd rect
			(at 0.40005 0)
			(size 0.4572 0.508)
			(layers "F.Cu" "F.Mask" "F.Paste")
			(net "P3V3_BLAD1")
		)
		(pad "2" smd rect
			(at -0.40005 0)
			(size 0.4572 0.508)
			(layers "F.Cu" "F.Mask" "F.Paste")
			(net "ENET10G_2_LOS")
		)
	)
	(footprint ""
		(layer "F.Cu")
		(at 119.433848 -22.239732 180)
		(property "Reference" "R68"
			(at 60.737496 -5.195316 0)
			(unlocked yes)
			(layer "F.SilkS")
			(effects
				(font
					(size 0.7874 0.5842)
					(thickness 0.1524)
				)
				(justify left)
			)
		)
		(property "Value" ""
			(at 0 0 180)
			(layer "F.Fab")
			(effects
				(font
					(size 1.27 1.27)
				)
			)
		)
		(duplicate_pad_numbers_are_jumpers no)
		(fp_line
			(start 0.7874 0.4064)
			(end -0.7874 0.4064)
			(stroke
				(width 0.1524)
				(type default)
			)
			(layer "F.SilkS")
		)
		(fp_line
			(start 0.7874 -0.4064)
			(end 0.7874 0.4064)
			(stroke
				(width 0.1524)
				(type default)
			)
			(layer "F.SilkS")
		)
		(fp_line
			(start -0.7874 0.4064)
			(end -0.7874 -0.4064)
			(stroke
				(width 0.1524)
				(type default)
			)
			(layer "F.SilkS")
		)
		(fp_line
			(start -0.7874 -0.4064)
			(end 0.7874 -0.4064)
			(stroke
				(width 0.1524)
				(type default)
			)
			(layer "F.SilkS")
		)
		(fp_poly
			(pts
				(xy -0.508 0.2794) (xy -0.508 0.2286) (xy -0.635 0.2286) (xy -0.635 -0.254) (xy -0.5334 -0.254)
				(xy -0.5334 -0.2794) (xy 0.5334 -0.2794) (xy 0.5334 -0.254) (xy 0.635 -0.254) (xy 0.635 0.254) (xy 0.5334 0.254)
				(xy 0.5334 0.2794)
			)
			(stroke
				(width 0)
				(type default)
			)
			(fill no)
			(layer "F.CrtYd")
		)
		(pad "1" smd rect
			(at 0.40005 0 180)
			(size 0.4572 0.508)
			(layers "F.Cu" "F.Mask" "F.Paste")
			(net "ENET10G_2_LOS")
		)
		(pad "2" smd rect
			(at -0.40005 0 180)
			(size 0.4572 0.508)
			(layers "F.Cu" "F.Mask" "F.Paste")
			(net "SFP2_PRESENT_N")
		)
	)
	(footprint ""
		(layer "F.Cu")
		(at 27.167332 -19.7358 -90)
		(property "Reference" "R90"
			(at 0.889 -5.364988 90)
			(unlocked yes)
			(layer "F.SilkS")
			(effects
				(font
					(size 0.7874 0.5842)
					(thickness 0.1524)
				)
				(justify left)
			)
		)
		(property "Value" ""
			(at 0 0 270)
			(layer "F.Fab")
			(effects
				(font
					(size 1.27 1.27)
				)
			)
		)
		(duplicate_pad_numbers_are_jumpers no)
		(fp_line
			(start -0.7874 0.4064)
			(end -0.7874 -0.4064)
			(stroke
				(width 0.1524)
				(type default)
			)
			(layer "F.SilkS")
		)
		(fp_line
			(start 0.7874 0.4064)
			(end -0.7874 0.4064)
			(stroke
				(width 0.1524)
				(type default)
			)
			(layer "F.SilkS")
		)
		(fp_line
			(start -0.7874 -0.4064)
			(end 0.7874 -0.4064)
			(stroke
				(width 0.1524)
				(type default)
			)
			(layer "F.SilkS")
		)
		(fp_line
			(start 0.7874 -0.4064)
			(end 0.7874 0.4064)
			(stroke
				(width 0.1524)
				(type default)
			)
			(layer "F.SilkS")
		)
		(fp_poly
			(pts
				(xy -0.508 0.2794) (xy -0.508 0.2286) (xy -0.635 0.2286) (xy -0.635 -0.254) (xy -0.5334 -0.254)
				(xy -0.5334 -0.2794) (xy 0.5334 -0.2794) (xy 0.5334 -0.254) (xy 0.635 -0.254) (xy 0.635 0.254) (xy 0.5334 0.254)
				(xy 0.5334 0.2794)
			)
			(stroke
				(width 0)
				(type default)
			)
			(fill no)
			(layer "F.CrtYd")
		)
		(pad "1" smd rect
			(at 0.40005 0 270)
			(size 0.4572 0.508)
			(layers "F.Cu" "F.Mask" "F.Paste")
			(net "N39398095")
		)
		(pad "2" smd rect
			(at -0.40005 0 270)
			(size 0.4572 0.508)
			(layers "F.Cu" "F.Mask" "F.Paste")
			(net "P12V")
		)
	)
	(footprint ""
		(layer "F.Cu")
		(at 122.747532 -21.750782 -90)
		(property "Reference" "R57"
			(at 6.163564 59.709812 90)
			(unlocked yes)
			(layer "F.SilkS")
			(effects
				(font
					(size 0.7874 0.5842)
					(thickness 0.1524)
				)
				(justify left)
			)
		)
		(property "Value" ""
			(at 0 0 270)
			(layer "F.Fab")
			(effects
				(font
					(size 1.27 1.27)
				)
			)
		)
		(duplicate_pad_numbers_are_jumpers no)
		(fp_line
			(start -0.7874 0.4064)
			(end -0.7874 -0.4064)
			(stroke
				(width 0.1524)
				(type default)
			)
			(layer "F.SilkS")
		)
		(fp_line
			(start 0.7874 0.4064)
			(end -0.7874 0.4064)
			(stroke
				(width 0.1524)
				(type default)
			)
			(layer "F.SilkS")
		)
		(fp_line
			(start -0.7874 -0.4064)
			(end 0.7874 -0.4064)
			(stroke
				(width 0.1524)
				(type default)
			)
			(layer "F.SilkS")
		)
		(fp_line
			(start 0.7874 -0.4064)
			(end 0.7874 0.4064)
			(stroke
				(width 0.1524)
				(type default)
			)
			(layer "F.SilkS")
		)
		(fp_poly
			(pts
				(xy -0.508 0.2794) (xy -0.508 0.2286) (xy -0.635 0.2286) (xy -0.635 -0.254) (xy -0.5334 -0.254)
				(xy -0.5334 -0.2794) (xy 0.5334 -0.2794) (xy 0.5334 -0.254) (xy 0.635 -0.254) (xy 0.635 0.254) (xy 0.5334 0.254)
				(xy 0.5334 0.2794)
			)
			(stroke
				(width 0)
				(type default)
			)
			(fill no)
			(layer "F.CrtYd")
		)
		(pad "1" smd rect
			(at 0.40005 0 270)
			(size 0.4572 0.508)
			(layers "F.Cu" "F.Mask" "F.Paste")
			(net "SKU_PIN_BLAD1_2")
		)
		(pad "2" smd rect
			(at -0.40005 0 270)
			(size 0.4572 0.508)
			(layers "F.Cu" "F.Mask" "F.Paste")
			(net "P3V3_BLAD1")
		)
	)
	(footprint ""
		(layer "F.Cu")
		(at 154.89936 -22.899878 180)
		(property "Reference" "R1"
			(at -33.93948 -17.844008 0)
			(unlocked yes)
			(layer "F.SilkS")
			(effects
				(font
					(size 0.7874 0.5842)
					(thickness 0.1524)
				)
				(justify left)
			)
		)
		(property "Value" ""
			(at 0 0 180)
			(layer "F.Fab")
			(effects
				(font
					(size 1.27 1.27)
				)
			)
		)
		(duplicate_pad_numbers_are_jumpers no)
		(fp_line
			(start 0.7874 0.4064)
			(end -0.7874 0.4064)
			(stroke
				(width 0.1524)
				(type default)
			)
			(layer "F.SilkS")
		)
		(fp_line
			(start 0.7874 -0.4064)
			(end 0.7874 0.4064)
			(stroke
				(width 0.1524)
				(type default)
			)
			(layer "F.SilkS")
		)
		(fp_line
			(start -0.7874 0.4064)
			(end -0.7874 -0.4064)
			(stroke
				(width 0.1524)
				(type default)
			)
			(layer "F.SilkS")
		)
		(fp_line
			(start -0.7874 -0.4064)
			(end 0.7874 -0.4064)
			(stroke
				(width 0.1524)
				(type default)
			)
			(layer "F.SilkS")
		)
		(fp_poly
			(pts
				(xy -0.508 0.2794) (xy -0.508 0.2286) (xy -0.635 0.2286) (xy -0.635 -0.254) (xy -0.5334 -0.254)
				(xy -0.5334 -0.2794) (xy 0.5334 -0.2794) (xy 0.5334 -0.254) (xy 0.635 -0.254) (xy 0.635 0.254) (xy 0.5334 0.254)
				(xy 0.5334 0.2794)
			)
			(stroke
				(width 0)
				(type default)
			)
			(fill no)
			(layer "F.CrtYd")
		)
		(pad "1" smd rect
			(at 0.40005 0 180)
			(size 0.4572 0.508)
			(layers "F.Cu" "F.Mask" "F.Paste")
			(net "P3V3_BLAD1")
		)
		(pad "2" smd rect
			(at -0.40005 0 180)
			(size 0.4572 0.508)
			(layers "F.Cu" "F.Mask" "F.Paste")
			(net "ENET10G_1_TX_FAULT")
		)
	)
	(footprint ""
		(layer "F.Cu")
		(at 127.141732 -21.750782 90)
		(property "Reference" "R38"
			(at -6.1722 -60.467748 90)
			(unlocked yes)
			(layer "F.SilkS")
			(effects
				(font
					(size 0.7874 0.5842)
					(thickness 0.1524)
				)
				(justify left)
			)
		)
		(property "Value" ""
			(at 0 0 90)
			(layer "F.Fab")
			(effects
				(font
					(size 1.27 1.27)
				)
			)
		)
		(duplicate_pad_numbers_are_jumpers no)
		(fp_line
			(start 0.7874 -0.4064)
			(end 0.7874 0.4064)
			(stroke
				(width 0.1524)
				(type default)
			)
			(layer "F.SilkS")
		)
		(fp_line
			(start -0.7874 -0.4064)
			(end 0.7874 -0.4064)
			(stroke
				(width 0.1524)
				(type default)
			)
			(layer "F.SilkS")
		)
		(fp_line
			(start 0.7874 0.4064)
			(end -0.7874 0.4064)
			(stroke
				(width 0.1524)
				(type default)
			)
			(layer "F.SilkS")
		)
		(fp_line
			(start -0.7874 0.4064)
			(end -0.7874 -0.4064)
			(stroke
				(width 0.1524)
				(type default)
			)
			(layer "F.SilkS")
		)
		(fp_poly
			(pts
				(xy -0.508 0.2794) (xy -0.508 0.2286) (xy -0.635 0.2286) (xy -0.635 -0.254) (xy -0.5334 -0.254)
				(xy -0.5334 -0.2794) (xy 0.5334 -0.2794) (xy 0.5334 -0.254) (xy 0.635 -0.254) (xy 0.635 0.254) (xy 0.5334 0.254)
				(xy 0.5334 0.2794)
			)
			(stroke
				(width 0)
				(type default)
			)
			(fill no)
			(layer "F.CrtYd")
		)
		(pad "1" smd rect
			(at 0.40005 0 90)
			(size 0.4572 0.508)
			(layers "F.Cu" "F.Mask" "F.Paste")
			(net "GND")
		)
		(pad "2" smd rect
			(at -0.40005 0 90)
			(size 0.4572 0.508)
			(layers "F.Cu" "F.Mask" "F.Paste")
			(net "SKU_PIN_BLAD1_1")
		)
	)
)
